(kicad_pcb
	(version 20260206)
	(generator "pcbnew")
	(generator_version "10.0")
	(general
		(thickness 1.6)
		(legacy_teardrops no)
	)
	(paper "A4")
	(title_block
		(title "dpb — 14545-sa.0730WZS0815.brd")
		(comment 1 "Honey Badger (Wiwynn) / footprints 152-154 of 1066")
	)
	(layers
		(0 "F.Cu" signal "TOP")
		(4 "In1.Cu" signal "L2GND")
		(6 "In2.Cu" signal "L3")
		(8 "In3.Cu" signal "L4VCC")
		(10 "In4.Cu" signal "L5VCC")
		(12 "In5.Cu" signal "L6")
		(14 "In6.Cu" signal "L7GND")
		(2 "B.Cu" signal "BOTTOM")
		(9 "F.Adhes" user "F.Adhesive")
		(11 "B.Adhes" user "B.Adhesive")
		(13 "F.Paste" user "Package Geometry/Pastemask Top")
		(15 "B.Paste" user "Package Geometry/Pastemask Bottom")
		(5 "F.SilkS" user "Ref Des/Silkscreen Top")
		(7 "B.SilkS" user "Ref Des/Silkscreen Bottom")
		(1 "F.Mask" user "Board Geometry/Soldermask Top")
		(3 "B.Mask" user "Board Geometry/Soldermask Bottom")
		(17 "Dwgs.User" user "User.Drawings")
		(19 "Cmts.User" user "User.Comments")
		(21 "Eco1.User" user "User.Eco1")
		(23 "Eco2.User" user "User.Eco2")
		(25 "Edge.Cuts" user "Board Geometry/Outline")
		(27 "Margin" user)
		(31 "F.CrtYd" user "Package Geometry/Place Bound Top")
		(29 "B.CrtYd" user "Package Geometry/Place Bound Bottom")
		(35 "F.Fab" user "Ref Des/Assembly Top")
		(33 "B.Fab" user "Ref Des/Assembly Bottom")
	)
	(footprint ""
		(layer "F.Cu")
		(at 85.343746 -17.0307 90)
		(property "Reference" "R475"
			(at 0 0 90)
			(layer "F.SilkS")
			(hide yes)
			(effects
				(font
					(size 1.27 1.27)
				)
			)
		)
		(property "Value" "4K7R2J-2-GP"
			(at 0.064008 -3.993896 90)
			(unlocked yes)
			(layer "F.Fab")
			(hide yes)
			(effects
				(font
					(size 1.016 1.016)
					(thickness 0.1524)
				)
			)
		)
		(property "Device Type" "R402H16"
			(at 0.064008 -5.517896 90)
			(unlocked yes)
			(layer "F.Fab")
			(hide yes)
			(effects
				(font
					(size 1.016 1.016)
					(thickness 0.1524)
				)
			)
		)
		(duplicate_pad_numbers_are_jumpers no)
		(fp_line
			(start 0.508 -0.9398)
			(end -0.508 -0.9398)
			(stroke
				(width 0.1524)
				(type default)
			)
			(layer "F.SilkS")
		)
		(fp_line
			(start -0.508 -0.9398)
			(end -0.508 0.9398)
			(stroke
				(width 0.1524)
				(type default)
			)
			(layer "F.SilkS")
		)
		(fp_rect
			(start -0.508 0.9398)
			(end 0.508 -0.9398)
			(stroke
				(width 0)
				(type default)
			)
			(fill no)
			(layer "F.CrtYd")
		)
		(fp_rect
			(start -0.508 0.9398)
			(end 0.508 -0.9398)
			(stroke
				(width 0)
				(type default)
			)
			(fill no)
			(layer "F.Fab")
		)
		(pad "1" smd custom
			(at 0 -0.4445 90)
			(size 0.1397 0.1397)
			(layers "F.Cu" "F.Mask" "F.Paste")
			(net "P3V3")
			(options
				(clearance outline)
				(anchor circle)
			)
			(primitives
				(gr_poly
					(pts
						(arc
							(start -0.1778 -0.2794)
							(mid -0.249642 -0.249642)
							(end -0.2794 -0.1778)
						)
						(arc
							(start -0.2794 0.1778)
							(mid -0.249642 0.249642)
							(end -0.1778 0.2794)
						)
						(arc
							(start 0.1778 0.2794)
							(mid 0.249642 0.249642)
							(end 0.2794 0.1778)
						)
						(arc
							(start 0.2794 -0.1778)
							(mid 0.249642 -0.249642)
							(end 0.1778 -0.2794)
						)
					)
					(width 0)
					(fill yes)
				)
			)
		)
		(pad "2" smd custom
			(at 0 0.4445 90)
			(size 0.1397 0.1397)
			(layers "F.Cu" "F.Mask" "F.Paste")
			(net "SAS2X28_B_HDD14_FLT")
			(options
				(clearance outline)
				(anchor circle)
			)
			(primitives
				(gr_poly
					(pts
						(arc
							(start -0.1778 -0.2794)
							(mid -0.249642 -0.249642)
							(end -0.2794 -0.1778)
						)
						(arc
							(start -0.2794 0.1778)
							(mid -0.249642 0.249642)
							(end -0.1778 0.2794)
						)
						(arc
							(start 0.1778 0.2794)
							(mid 0.249642 0.249642)
							(end 0.2794 0.1778)
						)
						(arc
							(start 0.2794 -0.1778)
							(mid 0.249642 -0.249642)
							(end 0.1778 -0.2794)
						)
					)
					(width 0)
					(fill yes)
				)
			)
		)
	)
	(footprint ""
		(layer "F.Cu")
		(at 42.500042 -170.669966 90)
		(property "Reference" "SKT9"
			(at 0 0 90)
			(layer "F.SilkS")
			(hide yes)
			(effects
				(font
					(size 1.27 1.27)
				)
			)
		)
		(property "Value" "SKT-SATA14P-15P-12-GP"
			(at -22.6187 8.1788 90)
			(unlocked yes)
			(layer "F.Fab")
			(hide yes)
			(effects
				(font
					(size 1.016 1.016)
					(thickness 0.1524)
				)
			)
		)
		(property "Device Type" "87945-1001"
			(at -22.6187 6.6548 90)
			(unlocked yes)
			(layer "F.Fab")
			(hide yes)
			(effects
				(font
					(size 1.016 1.016)
					(thickness 0.1524)
				)
			)
		)
		(duplicate_pad_numbers_are_jumpers no)
		(fp_line
			(start -15.3924 -5.8547)
			(end -16.3576 -5.8547)
			(stroke
				(width 0.3302)
				(type default)
			)
			(layer "F.SilkS")
		)
		(fp_line
			(start 20.4724 -5.7658)
			(end 20.4724 -2.3114)
			(stroke
				(width 0.1524)
				(type default)
			)
			(layer "F.SilkS")
		)
		(fp_line
			(start -20.4724 -5.7658)
			(end 20.4724 -5.7658)
			(stroke
				(width 0.1524)
				(type default)
			)
			(layer "F.SilkS")
		)
		(fp_line
			(start 23.7617 -2.3114)
			(end 23.7617 2.3114)
			(stroke
				(width 0.1524)
				(type default)
			)
			(layer "F.SilkS")
		)
		(fp_line
			(start 20.4724 -2.3114)
			(end 23.7617 -2.3114)
			(stroke
				(width 0.1524)
				(type default)
			)
			(layer "F.SilkS")
		)
		(fp_line
			(start -20.4724 -2.3114)
			(end -20.4724 -5.7658)
			(stroke
				(width 0.1524)
				(type default)
			)
			(layer "F.SilkS")
		)
		(fp_line
			(start -23.7617 -2.3114)
			(end -20.4724 -2.3114)
			(stroke
				(width 0.1524)
				(type default)
			)
			(layer "F.SilkS")
		)
		(fp_line
			(start 23.117556 -0.5461)
			(end 23.117556 0.5461)
			(stroke
				(width 0.3048)
				(type default)
			)
			(layer "F.SilkS")
		)
		(fp_line
			(start -20.882356 -0.5461)
			(end -20.882356 0.5461)
			(stroke
				(width 0.3048)
				(type default)
			)
			(layer "F.SilkS")
		)
		(fp_line
			(start 20.882356 0.5461)
			(end 20.882356 -0.5461)
			(stroke
				(width 0.3048)
				(type default)
			)
			(layer "F.SilkS")
		)
		(fp_line
			(start -23.117556 0.5461)
			(end -23.117556 -0.5461)
			(stroke
				(width 0.3048)
				(type default)
			)
			(layer "F.SilkS")
		)
		(fp_line
			(start 23.7617 2.3114)
			(end 20.4724 2.3114)
			(stroke
				(width 0.1524)
				(type default)
			)
			(layer "F.SilkS")
		)
		(fp_line
			(start 20.4724 2.3114)
			(end 20.4724 9.652)
			(stroke
				(width 0.1524)
				(type default)
			)
			(layer "F.SilkS")
		)
		(fp_line
			(start -20.4724 2.3114)
			(end -23.7617 2.3114)
			(stroke
				(width 0.1524)
				(type default)
			)
			(layer "F.SilkS")
		)
		(fp_line
			(start -23.7617 2.3114)
			(end -23.7617 -2.3114)
			(stroke
				(width 0.1524)
				(type default)
			)
			(layer "F.SilkS")
		)
		(fp_line
			(start 17.8435 7.9502)
			(end -17.8435 7.9502)
			(stroke
				(width 0.1524)
				(type default)
			)
			(layer "F.SilkS")
		)
		(fp_line
			(start -17.8435 7.9502)
			(end -17.8435 9.652)
			(stroke
				(width 0.1524)
				(type default)
			)
			(layer "F.SilkS")
		)
		(fp_line
			(start 20.4724 9.652)
			(end 17.8435 9.652)
			(stroke
				(width 0.1524)
				(type default)
			)
			(layer "F.SilkS")
		)
		(fp_line
			(start 17.8435 9.652)
			(end 17.8435 7.9502)
			(stroke
				(width 0.1524)
				(type default)
			)
			(layer "F.SilkS")
		)
		(fp_line
			(start -17.8435 9.652)
			(end -20.4724 9.652)
			(stroke
				(width 0.1524)
				(type default)
			)
			(layer "F.SilkS")
		)
		(fp_line
			(start -20.4724 9.652)
			(end -20.4724 2.3114)
			(stroke
				(width 0.1524)
				(type default)
			)
			(layer "F.SilkS")
		)
		(fp_arc
			(start 20.882356 -0.5461)
			(mid 21.999956 -1.6637)
			(end 23.117556 -0.5461)
			(stroke
				(width 0.3048)
				(type default)
			)
			(layer "F.SilkS")
		)
		(fp_arc
			(start -23.117556 -0.5461)
			(mid -21.999956 -1.6637)
			(end -20.882356 -0.5461)
			(stroke
				(width 0.3048)
				(type default)
			)
			(layer "F.SilkS")
		)
		(fp_arc
			(start 23.117556 0.5461)
			(mid 21.999956 1.6637)
			(end 20.882356 0.5461)
			(stroke
				(width 0.3048)
				(type default)
			)
			(layer "F.SilkS")
		)
		(fp_arc
			(start -20.882356 0.5461)
			(mid -21.999956 1.6637)
			(end -23.117556 0.5461)
			(stroke
				(width 0.3048)
				(type default)
			)
			(layer "F.SilkS")
		)
		(fp_poly
			(pts
				(xy -15.87119 -5.838698) (xy -15.23619 -6.473698) (xy -16.50619 -6.473698)
			)
			(stroke
				(width 0)
				(type default)
			)
			(fill yes)
			(layer "F.SilkS")
		)
		(fp_poly
			(pts
				(xy -20.2184 -5.5118) (xy 20.2184 -5.5118) (xy 20.2184 -2.0574) (xy 23.5077 -2.0574) (xy 23.5077 2.0574)
				(xy 20.2184 2.0574) (xy 20.2184 9.398) (xy 18.0975 9.398) (xy 18.0975 7.6962) (xy -18.0975 7.6962)
				(xy -18.0975 9.398) (xy -20.2184 9.398) (xy -20.2184 2.0574) (xy -23.5077 2.0574) (xy -23.5077 -2.0574)
				(xy -20.2184 -2.0574)
			)
			(stroke
				(width 0)
				(type default)
			)
			(fill no)
			(layer "F.CrtYd")
		)
		(fp_poly
			(pts
				(xy -20.2184 -5.5118) (xy -20.2184 -6.0198) (xy -20.7264 -6.0198) (xy -20.7264 -2.5654) (xy -24.0157 -2.5654)
				(xy -24.0157 2.5654) (xy -20.7264 2.5654) (xy -20.7264 9.906) (xy -17.5895 9.906) (xy -17.5895 8.2042)
				(xy 17.5895 8.2042) (xy 17.5895 9.906) (xy 20.7264 9.906) (xy 20.7264 2.5654) (xy 24.0157 2.5654)
				(xy 24.0157 -2.5654) (xy 20.7264 -2.5654) (xy 20.7264 -6.0198) (xy -20.21586 -6.0198) (xy -20.21586 -5.5118)
				(xy 20.2184 -5.5118) (xy 20.2184 -2.0574) (xy 23.5077 -2.0574) (xy 23.5077 2.0574) (xy 20.2184 2.0574)
				(xy 20.2184 9.398) (xy 18.0975 9.398) (xy 18.0975 7.6962) (xy -18.0975 7.6962) (xy -18.0975 9.398)
				(xy -20.2184 9.398) (xy -20.2184 2.0574) (xy -23.5077 2.0574) (xy -23.5077 -2.0574) (xy -20.2184 -2.0574)
			)
			(stroke
				(width 0)
				(type default)
			)
			(fill no)
			(layer "F.CrtYd")
		)
		(fp_poly
			(pts
				(xy -20.7264 -6.0198) (xy -20.7264 -2.5654) (xy -24.0157 -2.5654) (xy -24.0157 2.5654) (xy -20.7264 2.5654)
				(xy -20.7264 9.906) (xy -17.5895 9.906) (xy -17.5895 8.2042) (xy 17.5895 8.2042) (xy 17.5895 9.906)
				(xy 20.7264 9.906) (xy 20.7264 2.5654) (xy 24.0157 2.5654) (xy 24.0157 -2.5654) (xy 20.7264 -2.5654)
				(xy 20.7264 -6.0198)
			)
			(stroke
				(width 0)
				(type default)
			)
			(fill no)
			(layer "F.Fab")
		)
		(pad "" np_thru_hole circle
			(at -18.999962 -2.350008 90)
			(size 0.254 0.254)
			(drill 1.8542)
			(layers "*.Cu" "*.Mask")
			(clearance 1.1557)
			(thermal_gap 1.1557)
		)
		(pad "" np_thru_hole circle
			(at 18.999962 -2.350008 90)
			(size 0.254 0.254)
			(drill 1.8542)
			(layers "*.Cu" "*.Mask")
			(clearance 1.1557)
			(thermal_gap 1.1557)
		)
		(pad "H1" thru_hole oval
			(at -21.999956 0 90)
			(size 1.524 2.6162)
			(drill oval 0.8128 1.905)
			(layers "*.Cu" "*.Mask")
			(remove_unused_layers no)
			(net "GND")
			(clearance 0.1524)
			(thermal_gap 0.1524)
		)
		(pad "H2" thru_hole oval
			(at 21.999956 0 90)
			(size 1.524 2.6162)
			(drill oval 0.8128 1.905)
			(layers "*.Cu" "*.Mask")
			(remove_unused_layers no)
			(net "GND")
			(clearance 0.1524)
			(thermal_gap 0.1524)
		)
		(pad "P1" smd rect
			(at -1.89992 -4.249928 90)
			(size 0.6604 2.3876)
			(layers "F.Cu" "F.Mask" "F.Paste")
			(net "Net_5")
		)
		(pad "P2" smd rect
			(at -0.62992 -4.249928 90)
			(size 0.6604 2.3876)
			(layers "F.Cu" "F.Mask" "F.Paste")
			(net "Net_4")
		)
		(pad "P3" smd rect
			(at 0.64008 -4.249928 90)
			(size 0.6604 2.3876)
			(layers "F.Cu" "F.Mask" "F.Paste")
			(net "Net_3")
		)
		(pad "P4" smd rect
			(at 1.91008 -4.249928 90)
			(size 0.6604 2.3876)
			(layers "F.Cu" "F.Mask" "F.Paste")
			(net "GND")
		)
		(pad "P5" smd rect
			(at 3.18008 -4.249928 90)
			(size 0.6604 2.3876)
			(layers "F.Cu" "F.Mask" "F.Paste")
			(net "HDD_PRSNT_NET8")
		)
		(pad "P6" smd rect
			(at 4.45008 -4.249928 90)
			(size 0.6604 2.3876)
			(layers "F.Cu" "F.Mask" "F.Paste")
			(net "GND")
		)
		(pad "P7" smd rect
			(at 5.72008 -4.249928 90)
			(size 0.6604 2.3876)
			(layers "F.Cu" "F.Mask" "F.Paste")
			(net "5V_PRE_8")
		)
		(pad "P8" smd rect
			(at 6.99008 -4.249928 90)
			(size 0.6604 2.3876)
			(layers "F.Cu" "F.Mask" "F.Paste")
			(net "P5V_HDD8")
		)
		(pad "P9" smd rect
			(at 8.26008 -4.249928 90)
			(size 0.6604 2.3876)
			(layers "F.Cu" "F.Mask" "F.Paste")
			(net "P5V_HDD8")
		)
		(pad "P10" smd rect
			(at 9.53008 -4.249928 90)
			(size 0.6604 2.3876)
			(layers "F.Cu" "F.Mask" "F.Paste")
			(net "GND")
		)
		(pad "P11" smd rect
			(at 10.80008 -4.249928 90)
			(size 0.6604 2.3876)
			(layers "F.Cu" "F.Mask" "F.Paste")
			(net "ACT_HDD8")
		)
		(pad "P12" smd rect
			(at 12.07008 -4.249928 90)
			(size 0.6604 2.3876)
			(layers "F.Cu" "F.Mask" "F.Paste")
			(net "GND")
		)
		(pad "P13" smd rect
			(at 13.34008 -4.249928 90)
			(size 0.6604 2.3876)
			(layers "F.Cu" "F.Mask" "F.Paste")
			(net "12V_PRE_8")
		)
		(pad "P14" smd rect
			(at 14.61008 -4.249928 90)
			(size 0.6604 2.3876)
			(layers "F.Cu" "F.Mask" "F.Paste")
			(net "P12V_HDD8")
		)
		(pad "P15" smd rect
			(at 15.88008 -4.249928 90)
			(size 0.6604 2.3876)
			(layers "F.Cu" "F.Mask" "F.Paste")
			(net "P12V_HDD8")
		)
		(pad "S1" smd rect
			(at -15.86992 -4.249928 90)
			(size 0.6604 2.3876)
			(layers "F.Cu" "F.Mask" "F.Paste")
			(net "GND")
		)
		(pad "S2" smd rect
			(at -14.59992 -4.249928 90)
			(size 0.6604 2.3876)
			(layers "F.Cu" "F.Mask" "F.Paste")
			(net "SAS2X28_A_HDD8_TX_+")
		)
		(pad "S3" smd rect
			(at -13.32992 -4.249928 90)
			(size 0.6604 2.3876)
			(layers "F.Cu" "F.Mask" "F.Paste")
			(net "SAS2X28_A_HDD8_TX_-")
		)
		(pad "S4" smd rect
			(at -12.05992 -4.249928 90)
			(size 0.6604 2.3876)
			(layers "F.Cu" "F.Mask" "F.Paste")
			(net "GND")
		)
		(pad "S5" smd rect
			(at -10.78992 -4.249928 90)
			(size 0.6604 2.3876)
			(layers "F.Cu" "F.Mask" "F.Paste")
			(net "SAS2X28_DRIVE_RX_N_A8")
		)
		(pad "S6" smd rect
			(at -9.51992 -4.249928 90)
			(size 0.6604 2.3876)
			(layers "F.Cu" "F.Mask" "F.Paste")
			(net "SAS2X28_DRIVE_RX_P_A8")
		)
		(pad "S7" smd rect
			(at -8.24992 -4.249928 90)
			(size 0.6604 2.3876)
			(layers "F.Cu" "F.Mask" "F.Paste")
			(net "GND")
		)
		(pad "S8" smd rect
			(at -7.480046 -2.100072 90)
			(size 0.508 1.905)
			(layers "F.Cu" "F.Mask" "F.Paste")
			(net "GND")
		)
		(pad "S9" smd rect
			(at -6.679946 -2.100072 90)
			(size 0.508 1.905)
			(layers "F.Cu" "F.Mask" "F.Paste")
			(net "SAS2X28_B_HDD8_TX_+")
		)
		(pad "S10" smd rect
			(at -5.8801 -2.100072 90)
			(size 0.508 1.905)
			(layers "F.Cu" "F.Mask" "F.Paste")
			(net "SAS2X28_B_HDD8_TX_-")
		)
		(pad "S11" smd rect
			(at -5.08 -2.100072 90)
			(size 0.508 1.905)
			(layers "F.Cu" "F.Mask" "F.Paste")
			(net "GND")
		)
		(pad "S12" smd rect
			(at -4.2799 -2.100072 90)
			(size 0.508 1.905)
			(layers "F.Cu" "F.Mask" "F.Paste")
			(net "SAS2X28_DRIVE_RX_N_B8")
		)
		(pad "S13" smd rect
			(at -3.480054 -2.100072 90)
			(size 0.508 1.905)
			(layers "F.Cu" "F.Mask" "F.Paste")
			(net "SAS2X28_DRIVE_RX_P_B8")
		)
		(pad "S14" smd rect
			(at -2.679954 -2.100072 90)
			(size 0.508 1.905)
			(layers "F.Cu" "F.Mask" "F.Paste")
			(net "GND")
		)
		(zone
			(layers "F.Cu" "B.Cu" "In1.Cu" "In2.Cu" "In3.Cu" "In4.Cu" "In5.Cu" "In6.Cu")
			(hatch none 0.5)
			(connect_pads
				(clearance 0)
			)
			(min_thickness 0.25)
			(keepout
				(tracks not_allowed)
				(vias allowed)
				(pads allowed)
				(copperpour not_allowed)
				(footprints allowed)
			)
			(placement
				(enabled no)
				(sheetname "")
			)
			(fill
				(thermal_gap 0.5)
				(thermal_bridge_width 0.5)
				(island_removal_mode 0)
			)
			(polygon
				(pts
					(arc
						(start 41.381934 -189.669928)
						(mid 38.918134 -189.669928)
						(end 41.381934 -189.669928)
					)
				)
			)
		)
		(zone
			(layers "F.Cu" "B.Cu" "In1.Cu" "In2.Cu" "In3.Cu" "In4.Cu" "In5.Cu" "In6.Cu")
			(hatch none 0.5)
			(connect_pads
				(clearance 0)
			)
			(min_thickness 0.25)
			(keepout
				(tracks not_allowed)
				(vias allowed)
				(pads allowed)
				(copperpour not_allowed)
				(footprints allowed)
			)
			(placement
				(enabled no)
				(sheetname "")
			)
			(fill
				(thermal_gap 0.5)
				(thermal_bridge_width 0.5)
				(island_removal_mode 0)
			)
			(polygon
				(pts
					(arc
						(start 41.381934 -151.670004)
						(mid 38.918134 -151.670004)
						(end 41.381934 -151.670004)
					)
				)
			)
		)
	)
	(footprint ""
		(layer "F.Cu")
		(at 53.212746 -25.2857 180)
		(property "Reference" "PR27"
			(at 0 0 180)
			(layer "F.SilkS")
			(hide yes)
			(effects
				(font
					(size 1.27 1.27)
				)
			)
		)
		(property "Value" "10KR2D-GP"
			(at 0.064008 -3.993896 180)
			(unlocked yes)
			(layer "F.Fab")
			(hide yes)
			(effects
				(font
					(size 1.016 1.016)
					(thickness 0.1524)
				)
			)
		)
		(property "Device Type" "R402H16"
			(at 0.064008 -5.517896 180)
			(unlocked yes)
			(layer "F.Fab")
			(hide yes)
			(effects
				(font
					(size 1.016 1.016)
					(thickness 0.1524)
				)
			)
		)
		(duplicate_pad_numbers_are_jumpers no)
		(fp_line
			(start 0.508 -0.9398)
			(end -0.508 -0.9398)
			(stroke
				(width 0.1524)
				(type default)
			)
			(layer "F.SilkS")
		)
		(fp_line
			(start -0.508 -0.9398)
			(end -0.508 0.9398)
			(stroke
				(width 0.1524)
				(type default)
			)
			(layer "F.SilkS")
		)
		(fp_rect
			(start -0.508 0.9398)
			(end 0.508 -0.9398)
			(stroke
				(width 0)
				(type default)
			)
			(fill no)
			(layer "F.CrtYd")
		)
		(fp_rect
			(start -0.508 0.9398)
			(end 0.508 -0.9398)
			(stroke
				(width 0)
				(type default)
			)
			(fill no)
			(layer "F.Fab")
		)
		(pad "1" smd custom
			(at 0 -0.4445 180)
			(size 0.1397 0.1397)
			(layers "F.Cu" "F.Mask" "F.Paste")
			(net "P5VB_VFB")
			(options
				(clearance outline)
				(anchor circle)
			)
			(primitives
				(gr_poly
					(pts
						(arc
							(start -0.1778 -0.2794)
							(mid -0.249642 -0.249642)
							(end -0.2794 -0.1778)
						)
						(arc
							(start -0.2794 0.1778)
							(mid -0.249642 0.249642)
							(end -0.1778 0.2794)
						)
						(arc
							(start 0.1778 0.2794)
							(mid 0.249642 0.249642)
							(end 0.2794 0.1778)
						)
						(arc
							(start 0.2794 -0.1778)
							(mid 0.249642 -0.249642)
							(end 0.1778 -0.2794)
						)
					)
					(width 0)
					(fill yes)
				)
			)
		)
		(pad "2" smd custom
			(at 0 0.4445 180)
			(size 0.1397 0.1397)
			(layers "F.Cu" "F.Mask" "F.Paste")
			(net "P5VB_AGND")
			(options
				(clearance outline)
				(anchor circle)
			)
			(primitives
				(gr_poly
					(pts
						(arc
							(start -0.1778 -0.2794)
							(mid -0.249642 -0.249642)
							(end -0.2794 -0.1778)
						)
						(arc
							(start -0.2794 0.1778)
							(mid -0.249642 0.249642)
							(end -0.1778 0.2794)
						)
						(arc
							(start 0.1778 0.2794)
							(mid 0.249642 0.249642)
							(end 0.2794 0.1778)
						)
						(arc
							(start 0.2794 -0.1778)
							(mid 0.249642 -0.249642)
							(end 0.1778 -0.2794)
						)
					)
					(width 0)
					(fill yes)
				)
			)
		)
	)
)
